# S9S_MB_2U (Grand Teton) — schematic netlist excerpt (pin names and nets, part order shuffled) for the footprints in the layout excerpt that follows; sources: Cadence DE-HDL packaged netlist, KiCad conversion of 03242023_DA0F0TMBIJ0_F0T_Motherboard_J_brd_V01_OCP.brd

PC254_P0_6  Q_CAP  1UF 16V 10% X6S  pkg C0402  page 269 : A = SW_P12V_PVCCIN_CPU0_FLT ; B = GND
PC225  Q_CAP  1UF 16V 10% X6S  pkg C0402  page 274 : A = PVCCINFAON_CPU0_VCC ; B = GND

(kicad_pcb
	(version 20260206)
	(generator "pcbnew")
	(generator_version "10.0")
	(general
		(thickness 1.6)
		(legacy_teardrops no)
	)
	(paper "A4")
	(title_block
		(title "03242023_DA0F0TMBIJ0_F0T_Motherboard_J_brd_V01_OCP.brd")
		(comment 1 "Grand Teton / footprints 3218-3219 of 6105")
	)
	(layers
		(0 "F.Cu" signal "TOP")
		(4 "In1.Cu" signal "GND")
		(6 "In2.Cu" signal "IN1")
		(8 "In3.Cu" signal "GND1")
		(10 "In4.Cu" signal "IN2")
		(12 "In5.Cu" signal "GND2")
		(14 "In6.Cu" signal "IN3")
		(16 "In7.Cu" signal "GND3")
		(18 "In8.Cu" signal "VCC")
		(20 "In9.Cu" signal "VCC1")
		(22 "In10.Cu" signal "GND4")
		(24 "In11.Cu" signal "IN4")
		(26 "In12.Cu" signal "GND5")
		(28 "In13.Cu" signal "IN5")
		(30 "In14.Cu" signal "GND6")
		(32 "In15.Cu" signal "IN6")
		(34 "In16.Cu" signal "GND7")
		(2 "B.Cu" signal "BOTTOM")
		(9 "F.Adhes" user "F.Adhesive")
		(11 "B.Adhes" user "B.Adhesive")
		(13 "F.Paste" user "Package Geometry/Pastemask Top")
		(15 "B.Paste" user "Package Geometry/Pastemask Bottom")
		(5 "F.SilkS" user "Ref Des/Silkscreen Top")
		(7 "B.SilkS" user "Ref Des/Silkscreen Bottom")
		(1 "F.Mask" user "Board Geometry/Soldermask Top")
		(3 "B.Mask" user "Board Geometry/Soldermask Bottom")
		(17 "Dwgs.User" user "User.Drawings")
		(19 "Cmts.User" user "User.Comments")
		(21 "Eco1.User" user "User.Eco1")
		(23 "Eco2.User" user "User.Eco2")
		(25 "Edge.Cuts" user "Board Geometry/Outline")
		(27 "Margin" user)
		(31 "F.CrtYd" user "Package Geometry/Place Bound Top")
		(29 "B.CrtYd" user "Package Geometry/Place Bound Bottom")
		(35 "F.Fab" user "Ref Des/Assembly Top")
		(33 "B.Fab" user "Ref Des/Assembly Bottom")
	)
	(footprint ""
		(layer "F.Cu")
		(at 420.682166 -134.130034 180)
		(property "Reference" "PC225"
			(at 0 0 180)
			(layer "F.SilkS")
			(hide yes)
			(effects
				(font
					(size 1.27 1.27)
				)
			)
		)
		(property "Value" ""
			(at 0 0 180)
			(layer "F.Fab")
			(effects
				(font
					(size 1.27 1.27)
				)
			)
		)
		(duplicate_pad_numbers_are_jumpers no)
		(fp_line
			(start 0.7874 0.4064)
			(end -0.7874 0.4064)
			(stroke
				(width 0.1524)
				(type default)
			)
			(layer "F.SilkS")
		)
		(fp_line
			(start 0.7874 -0.4064)
			(end 0.7874 0.4064)
			(stroke
				(width 0.1524)
				(type default)
			)
			(layer "F.SilkS")
		)
		(fp_line
			(start -0.7874 0.4064)
			(end -0.7874 -0.4064)
			(stroke
				(width 0.1524)
				(type default)
			)
			(layer "F.SilkS")
		)
		(fp_line
			(start -0.7874 -0.4064)
			(end 0.7874 -0.4064)
			(stroke
				(width 0.1524)
				(type default)
			)
			(layer "F.SilkS")
		)
		(fp_line
			(start 0.67945 0.3048)
			(end 0.120396 0.3048)
			(stroke
				(width 0.1)
				(type default)
			)
			(layer "F.Fab")
		)
		(fp_line
			(start 0.67945 -0.3048)
			(end 0.67945 0.3048)
			(stroke
				(width 0.1)
				(type default)
			)
			(layer "F.Fab")
		)
		(fp_line
			(start 0.12065 -0.2794)
			(end 0.12065 -0.3048)
			(stroke
				(width 0.1)
				(type default)
			)
			(layer "F.Fab")
		)
		(fp_line
			(start 0.12065 -0.3048)
			(end 0.67945 -0.3048)
			(stroke
				(width 0.1)
				(type default)
			)
			(layer "F.Fab")
		)
		(fp_line
			(start 0.120396 0.3048)
			(end 0.120396 0.2794)
			(stroke
				(width 0.1)
				(type default)
			)
			(layer "F.Fab")
		)
		(fp_line
			(start 0.120396 0.2794)
			(end -0.12065 0.2794)
			(stroke
				(width 0.1)
				(type default)
			)
			(layer "F.Fab")
		)
		(fp_line
			(start -0.12065 0.3048)
			(end -0.67945 0.3048)
			(stroke
				(width 0.1)
				(type default)
			)
			(layer "F.Fab")
		)
		(fp_line
			(start -0.12065 0.2794)
			(end -0.12065 0.3048)
			(stroke
				(width 0.1)
				(type default)
			)
			(layer "F.Fab")
		)
		(fp_line
			(start -0.12065 -0.2794)
			(end 0.12065 -0.2794)
			(stroke
				(width 0.1)
				(type default)
			)
			(layer "F.Fab")
		)
		(fp_line
			(start -0.12065 -0.305054)
			(end -0.12065 -0.2794)
			(stroke
				(width 0.1)
				(type default)
			)
			(layer "F.Fab")
		)
		(fp_line
			(start -0.67945 0.3048)
			(end -0.67945 -0.305054)
			(stroke
				(width 0.1)
				(type default)
			)
			(layer "F.Fab")
		)
		(fp_line
			(start -0.67945 -0.305054)
			(end -0.12065 -0.305054)
			(stroke
				(width 0.1)
				(type default)
			)
			(layer "F.Fab")
		)
		(pad "1" smd circle
			(at -0.40005 0 180)
			(size 0 0)
			(layers "F.Cu" "F.Mask" "F.Paste")
			(net "PVCCINFAON_CPU0_VCC")
		)
		(pad "2" smd circle
			(at 0.40005 0 180)
			(size 0 0)
			(layers "F.Cu" "F.Mask" "F.Paste")
			(net "GND")
		)
	)
	(footprint ""
		(layer "F.Cu")
		(at 340.346284 -337.214718 -90)
		(property "Reference" "PC254_P0_6"
			(at 0 0 270)
			(layer "F.SilkS")
			(hide yes)
			(effects
				(font
					(size 1.27 1.27)
				)
			)
		)
		(property "Value" ""
			(at 0 0 270)
			(layer "F.Fab")
			(effects
				(font
					(size 1.27 1.27)
				)
			)
		)
		(duplicate_pad_numbers_are_jumpers no)
		(fp_line
			(start -0.7874 0.4064)
			(end -0.7874 -0.4064)
			(stroke
				(width 0.1524)
				(type default)
			)
			(layer "F.SilkS")
		)
		(fp_line
			(start 0.7874 0.4064)
			(end -0.7874 0.4064)
			(stroke
				(width 0.1524)
				(type default)
			)
			(layer "F.SilkS")
		)
		(fp_line
			(start -0.7874 -0.4064)
			(end 0.7874 -0.4064)
			(stroke
				(width 0.1524)
				(type default)
			)
			(layer "F.SilkS")
		)
		(fp_line
			(start 0.7874 -0.4064)
			(end 0.7874 0.4064)
			(stroke
				(width 0.1524)
				(type default)
			)
			(layer "F.SilkS")
		)
		(fp_line
			(start -0.67945 0.3048)
			(end -0.67945 -0.305054)
			(stroke
				(width 0.1)
				(type default)
			)
			(layer "F.Fab")
		)
		(fp_line
			(start -0.12065 0.3048)
			(end -0.67945 0.3048)
			(stroke
				(width 0.1)
				(type default)
			)
			(layer "F.Fab")
		)
		(fp_line
			(start 0.120396 0.3048)
			(end 0.120396 0.2794)
			(stroke
				(width 0.1)
				(type default)
			)
			(layer "F.Fab")
		)
		(fp_line
			(start 0.67945 0.3048)
			(end 0.120396 0.3048)
			(stroke
				(width 0.1)
				(type default)
			)
			(layer "F.Fab")
		)
		(fp_line
			(start -0.12065 0.2794)
			(end -0.12065 0.3048)
			(stroke
				(width 0.1)
				(type default)
			)
			(layer "F.Fab")
		)
		(fp_line
			(start 0.120396 0.2794)
			(end -0.12065 0.2794)
			(stroke
				(width 0.1)
				(type default)
			)
			(layer "F.Fab")
		)
		(fp_line
			(start -0.12065 -0.2794)
			(end 0.12065 -0.2794)
			(stroke
				(width 0.1)
				(type default)
			)
			(layer "F.Fab")
		)
		(fp_line
			(start 0.12065 -0.2794)
			(end 0.12065 -0.3048)
			(stroke
				(width 0.1)
				(type default)
			)
			(layer "F.Fab")
		)
		(fp_line
			(start 0.12065 -0.3048)
			(end 0.67945 -0.3048)
			(stroke
				(width 0.1)
				(type default)
			)
			(layer "F.Fab")
		)
		(fp_line
			(start 0.67945 -0.3048)
			(end 0.67945 0.3048)
			(stroke
				(width 0.1)
				(type default)
			)
			(layer "F.Fab")
		)
		(fp_line
			(start -0.67945 -0.305054)
			(end -0.12065 -0.305054)
			(stroke
				(width 0.1)
				(type default)
			)
			(layer "F.Fab")
		)
		(fp_line
			(start -0.12065 -0.305054)
			(end -0.12065 -0.2794)
			(stroke
				(width 0.1)
				(type default)
			)
			(layer "F.Fab")
		)
		(pad "1" smd circle
			(at -0.40005 0 270)
			(size 0 0)
			(layers "F.Cu" "F.Mask" "F.Paste")
			(net "SW_P12V_PVCCIN_CPU0_FLT")
		)
		(pad "2" smd circle
			(at 0.40005 0 270)
			(size 0 0)
			(layers "F.Cu" "F.Mask" "F.Paste")
			(net "GND")
		)
	)
)
